# T6G (Grand Teton) — schematic netlist excerpt (pin names and nets, part order shuffled) for the footprints in the layout excerpt that follows; sources: Cadence DE-HDL packaged netlist, KiCad conversion of 04192023_DAF0TMB3IC0_F0TG_MB_C_brd_V02_OCP.brd

C420  Q_CAP  10UF 6.3V 20% X6S  pkg C0402  page 345 : A = P0V9_CPU1_RT2_2A ; B = GND
R65  Q_RES  33.2 1% CHIP  pkg 0402LF  page 250 : A = SMB_PCIE0_3V3AUX_SCL ; B = SMB_PCIE0_3V3AUX_SCL_R

(kicad_pcb
	(version 20260206)
	(generator "pcbnew")
	(generator_version "10.0")
	(general
		(thickness 1.6)
		(legacy_teardrops no)
	)
	(paper "A4")
	(title_block
		(title "04192023_DAF0TMB3IC0_F0TG_MB_C_brd_V02_OCP.brd")
		(comment 1 "Grand Teton / footprints 5029-5030 of 8354")
	)
	(layers
		(0 "F.Cu" signal "TOP")
		(4 "In1.Cu" signal "GND")
		(6 "In2.Cu" signal "IN1")
		(8 "In3.Cu" signal "GND1")
		(10 "In4.Cu" signal "IN2")
		(12 "In5.Cu" signal "GND2")
		(14 "In6.Cu" signal "IN3")
		(16 "In7.Cu" signal "GND3")
		(18 "In8.Cu" signal "VCC")
		(20 "In9.Cu" signal "VCC1")
		(22 "In10.Cu" signal "GND4")
		(24 "In11.Cu" signal "IN4")
		(26 "In12.Cu" signal "GND5")
		(28 "In13.Cu" signal "IN5")
		(30 "In14.Cu" signal "GND6")
		(32 "In15.Cu" signal "IN6")
		(34 "In16.Cu" signal "GND7")
		(2 "B.Cu" signal "BOTTOM")
		(9 "F.Adhes" user "F.Adhesive")
		(11 "B.Adhes" user "B.Adhesive")
		(13 "F.Paste" user "Package Geometry/Pastemask Top")
		(15 "B.Paste" user "Package Geometry/Pastemask Bottom")
		(5 "F.SilkS" user "Ref Des/Silkscreen Top")
		(7 "B.SilkS" user "Ref Des/Silkscreen Bottom")
		(1 "F.Mask" user "Board Geometry/Soldermask Top")
		(3 "B.Mask" user "Board Geometry/Soldermask Bottom")
		(17 "Dwgs.User" user "User.Drawings")
		(19 "Cmts.User" user "User.Comments")
		(21 "Eco1.User" user "User.Eco1")
		(23 "Eco2.User" user "User.Eco2")
		(25 "Edge.Cuts" user "Board Geometry/Outline")
		(27 "Margin" user)
		(31 "F.CrtYd" user "Package Geometry/Place Bound Top")
		(29 "B.CrtYd" user "Package Geometry/Place Bound Bottom")
		(35 "F.Fab" user "Ref Des/Assembly Top")
		(33 "B.Fab" user "Ref Des/Assembly Bottom")
	)
	(footprint ""
		(layer "B.Cu")
		(at 161.419032 -390.560052 90)
		(property "Reference" "C420"
			(at 0 0 90)
			(layer "B.SilkS")
			(hide yes)
			(effects
				(font
					(size 1.27 1.27)
				)
				(justify mirror)
			)
		)
		(property "Value" ""
			(at 0 0 90)
			(layer "B.Fab")
			(effects
				(font
					(size 1.27 1.27)
				)
				(justify mirror)
			)
		)
		(duplicate_pad_numbers_are_jumpers no)
		(fp_line
			(start 0.7874 -0.4064)
			(end -0.7874 -0.4064)
			(stroke
				(width 0.1524)
				(type default)
			)
			(layer "B.SilkS")
		)
		(fp_line
			(start -0.7874 -0.4064)
			(end -0.7874 0.4064)
			(stroke
				(width 0.1524)
				(type default)
			)
			(layer "B.SilkS")
		)
		(fp_line
			(start 0.7874 0.4064)
			(end 0.7874 -0.4064)
			(stroke
				(width 0.1524)
				(type default)
			)
			(layer "B.SilkS")
		)
		(fp_line
			(start -0.7874 0.4064)
			(end 0.7874 0.4064)
			(stroke
				(width 0.1524)
				(type default)
			)
			(layer "B.SilkS")
		)
		(fp_line
			(start 0.67945 -0.305054)
			(end 0.12065 -0.305054)
			(stroke
				(width 0.1)
				(type default)
			)
			(layer "B.Fab")
		)
		(fp_line
			(start 0.12065 -0.305054)
			(end 0.12065 -0.2794)
			(stroke
				(width 0.1)
				(type default)
			)
			(layer "B.Fab")
		)
		(fp_line
			(start -0.12065 -0.3048)
			(end -0.67945 -0.3048)
			(stroke
				(width 0.1)
				(type default)
			)
			(layer "B.Fab")
		)
		(fp_line
			(start -0.67945 -0.3048)
			(end -0.67945 0.3048)
			(stroke
				(width 0.1)
				(type default)
			)
			(layer "B.Fab")
		)
		(fp_line
			(start 0.12065 -0.2794)
			(end -0.12065 -0.2794)
			(stroke
				(width 0.1)
				(type default)
			)
			(layer "B.Fab")
		)
		(fp_line
			(start -0.12065 -0.2794)
			(end -0.12065 -0.3048)
			(stroke
				(width 0.1)
				(type default)
			)
			(layer "B.Fab")
		)
		(fp_line
			(start 0.12065 0.2794)
			(end 0.12065 0.3048)
			(stroke
				(width 0.1)
				(type default)
			)
			(layer "B.Fab")
		)
		(fp_line
			(start -0.120396 0.2794)
			(end 0.12065 0.2794)
			(stroke
				(width 0.1)
				(type default)
			)
			(layer "B.Fab")
		)
		(fp_line
			(start 0.67945 0.3048)
			(end 0.67945 -0.305054)
			(stroke
				(width 0.1)
				(type default)
			)
			(layer "B.Fab")
		)
		(fp_line
			(start 0.12065 0.3048)
			(end 0.67945 0.3048)
			(stroke
				(width 0.1)
				(type default)
			)
			(layer "B.Fab")
		)
		(fp_line
			(start -0.120396 0.3048)
			(end -0.120396 0.2794)
			(stroke
				(width 0.1)
				(type default)
			)
			(layer "B.Fab")
		)
		(fp_line
			(start -0.67945 0.3048)
			(end -0.120396 0.3048)
			(stroke
				(width 0.1)
				(type default)
			)
			(layer "B.Fab")
		)
		(pad "1" smd circle
			(at 0.40005 0 270)
			(size 0 0)
			(layers "B.Cu" "B.Mask" "B.Paste")
			(net "P0V9_CPU1_RT2_2A")
		)
		(pad "2" smd circle
			(at -0.40005 0 270)
			(size 0 0)
			(layers "B.Cu" "B.Mask" "B.Paste")
			(net "GND")
		)
	)
	(footprint ""
		(layer "B.Cu")
		(at 165.58514 -9.013444 90)
		(property "Reference" "R65"
			(at 0 0 90)
			(layer "B.SilkS")
			(hide yes)
			(effects
				(font
					(size 1.27 1.27)
				)
				(justify mirror)
			)
		)
		(property "Value" ""
			(at 0 0 90)
			(layer "B.Fab")
			(effects
				(font
					(size 1.27 1.27)
				)
				(justify mirror)
			)
		)
		(duplicate_pad_numbers_are_jumpers no)
		(fp_line
			(start 0.7874 -0.4064)
			(end -0.7874 -0.4064)
			(stroke
				(width 0.1524)
				(type default)
			)
			(layer "B.SilkS")
		)
		(fp_line
			(start -0.7874 -0.4064)
			(end -0.7874 0.4064)
			(stroke
				(width 0.1524)
				(type default)
			)
			(layer "B.SilkS")
		)
		(fp_line
			(start 0.7874 0.4064)
			(end 0.7874 -0.4064)
			(stroke
				(width 0.1524)
				(type default)
			)
			(layer "B.SilkS")
		)
		(fp_line
			(start -0.7874 0.4064)
			(end 0.7874 0.4064)
			(stroke
				(width 0.1524)
				(type default)
			)
			(layer "B.SilkS")
		)
		(fp_line
			(start 0.67945 -0.305054)
			(end 0.12065 -0.305054)
			(stroke
				(width 0.1)
				(type default)
			)
			(layer "B.Fab")
		)
		(fp_line
			(start 0.12065 -0.305054)
			(end 0.12065 -0.2794)
			(stroke
				(width 0.1)
				(type default)
			)
			(layer "B.Fab")
		)
		(fp_line
			(start -0.12065 -0.3048)
			(end -0.67945 -0.3048)
			(stroke
				(width 0.1)
				(type default)
			)
			(layer "B.Fab")
		)
		(fp_line
			(start -0.67945 -0.3048)
			(end -0.67945 0.3048)
			(stroke
				(width 0.1)
				(type default)
			)
			(layer "B.Fab")
		)
		(fp_line
			(start 0.12065 -0.2794)
			(end -0.12065 -0.2794)
			(stroke
				(width 0.1)
				(type default)
			)
			(layer "B.Fab")
		)
		(fp_line
			(start -0.12065 -0.2794)
			(end -0.12065 -0.3048)
			(stroke
				(width 0.1)
				(type default)
			)
			(layer "B.Fab")
		)
		(fp_line
			(start 0.12065 0.2794)
			(end 0.12065 0.3048)
			(stroke
				(width 0.1)
				(type default)
			)
			(layer "B.Fab")
		)
		(fp_line
			(start -0.120396 0.2794)
			(end 0.12065 0.2794)
			(stroke
				(width 0.1)
				(type default)
			)
			(layer "B.Fab")
		)
		(fp_line
			(start 0.67945 0.3048)
			(end 0.67945 -0.305054)
			(stroke
				(width 0.1)
				(type default)
			)
			(layer "B.Fab")
		)
		(fp_line
			(start 0.12065 0.3048)
			(end 0.67945 0.3048)
			(stroke
				(width 0.1)
				(type default)
			)
			(layer "B.Fab")
		)
		(fp_line
			(start -0.120396 0.3048)
			(end -0.120396 0.2794)
			(stroke
				(width 0.1)
				(type default)
			)
			(layer "B.Fab")
		)
		(fp_line
			(start -0.67945 0.3048)
			(end -0.120396 0.3048)
			(stroke
				(width 0.1)
				(type default)
			)
			(layer "B.Fab")
		)
		(pad "1" smd circle
			(at 0.40005 0 270)
			(size 0 0)
			(layers "B.Cu" "B.Mask" "B.Paste")
			(net "SMB_PCIE0_3V3AUX_SCL")
		)
		(pad "2" smd circle
			(at -0.40005 0 270)
			(size 0 0)
			(layers "B.Cu" "B.Mask" "B.Paste")
			(net "SMB_PCIE0_3V3AUX_SCL_R")
		)
	)
)
